# T6G (Grand Teton) — schematic netlist excerpt (pin names and nets, part order shuffled) for the footprints in the layout excerpt that follows; sources: Cadence DE-HDL packaged netlist, KiCad conversion of 04192023_DAF0TMB3IC0_F0TG_MB_C_brd_V02_OCP.brd

R6765  Q_RES  1K 1% CHIP  pkg 0201LF  page 184 : A = P1V8_CPU0_RT_1D ; B = SMB_RT_CPU0_P1_R_SCL
R6043  Q_RES  100K 1% CHIP  pkg 0402LF  page 167 : A = GND ; B = FPGA_DEBUG_SW_SPARE
R8243  Q_RES  33 5% CHIP  pkg 0402LF  page 217 : A = PWRGD_PVDDIO_P1 ; B = PWRGD_PVDDIO_P1_R

(kicad_pcb
	(version 20260206)
	(generator "pcbnew")
	(generator_version "10.0")
	(general
		(thickness 1.6)
		(legacy_teardrops no)
	)
	(paper "A4")
	(title_block
		(title "04192023_DAF0TMB3IC0_F0TG_MB_C_brd_V02_OCP.brd")
		(comment 1 "Grand Teton / footprints 7570-7572 of 8354")
	)
	(layers
		(0 "F.Cu" signal "TOP")
		(4 "In1.Cu" signal "GND")
		(6 "In2.Cu" signal "IN1")
		(8 "In3.Cu" signal "GND1")
		(10 "In4.Cu" signal "IN2")
		(12 "In5.Cu" signal "GND2")
		(14 "In6.Cu" signal "IN3")
		(16 "In7.Cu" signal "GND3")
		(18 "In8.Cu" signal "VCC")
		(20 "In9.Cu" signal "VCC1")
		(22 "In10.Cu" signal "GND4")
		(24 "In11.Cu" signal "IN4")
		(26 "In12.Cu" signal "GND5")
		(28 "In13.Cu" signal "IN5")
		(30 "In14.Cu" signal "GND6")
		(32 "In15.Cu" signal "IN6")
		(34 "In16.Cu" signal "GND7")
		(2 "B.Cu" signal "BOTTOM")
		(9 "F.Adhes" user "F.Adhesive")
		(11 "B.Adhes" user "B.Adhesive")
		(13 "F.Paste" user "Package Geometry/Pastemask Top")
		(15 "B.Paste" user "Package Geometry/Pastemask Bottom")
		(5 "F.SilkS" user "Ref Des/Silkscreen Top")
		(7 "B.SilkS" user "Ref Des/Silkscreen Bottom")
		(1 "F.Mask" user "Board Geometry/Soldermask Top")
		(3 "B.Mask" user "Board Geometry/Soldermask Bottom")
		(17 "Dwgs.User" user "User.Drawings")
		(19 "Cmts.User" user "User.Comments")
		(21 "Eco1.User" user "User.Eco1")
		(23 "Eco2.User" user "User.Eco2")
		(25 "Edge.Cuts" user "Board Geometry/Outline")
		(27 "Margin" user)
		(31 "F.CrtYd" user "Package Geometry/Place Bound Top")
		(29 "B.CrtYd" user "Package Geometry/Place Bound Bottom")
		(35 "F.Fab" user "Ref Des/Assembly Top")
		(33 "B.Fab" user "Ref Des/Assembly Bottom")
	)
	(footprint ""
		(layer "B.Cu")
		(at 24.765 -361.061 180)
		(property "Reference" "R8243"
			(at 0 0 0)
			(layer "B.SilkS")
			(hide yes)
			(effects
				(font
					(size 1.27 1.27)
				)
				(justify mirror)
			)
		)
		(property "Value" ""
			(at 0 0 0)
			(layer "B.Fab")
			(effects
				(font
					(size 1.27 1.27)
				)
				(justify mirror)
			)
		)
		(duplicate_pad_numbers_are_jumpers no)
		(fp_line
			(start 0.7874 0.4064)
			(end 0.7874 -0.4064)
			(stroke
				(width 0.1524)
				(type default)
			)
			(layer "B.SilkS")
		)
		(fp_line
			(start 0.7874 -0.4064)
			(end -0.7874 -0.4064)
			(stroke
				(width 0.1524)
				(type default)
			)
			(layer "B.SilkS")
		)
		(fp_line
			(start -0.7874 0.4064)
			(end 0.7874 0.4064)
			(stroke
				(width 0.1524)
				(type default)
			)
			(layer "B.SilkS")
		)
		(fp_line
			(start -0.7874 -0.4064)
			(end -0.7874 0.4064)
			(stroke
				(width 0.1524)
				(type default)
			)
			(layer "B.SilkS")
		)
		(fp_line
			(start 0.67945 0.3048)
			(end 0.67945 -0.305054)
			(stroke
				(width 0.1)
				(type default)
			)
			(layer "B.Fab")
		)
		(fp_line
			(start 0.67945 -0.305054)
			(end 0.12065 -0.305054)
			(stroke
				(width 0.1)
				(type default)
			)
			(layer "B.Fab")
		)
		(fp_line
			(start 0.12065 0.3048)
			(end 0.67945 0.3048)
			(stroke
				(width 0.1)
				(type default)
			)
			(layer "B.Fab")
		)
		(fp_line
			(start 0.12065 0.2794)
			(end 0.12065 0.3048)
			(stroke
				(width 0.1)
				(type default)
			)
			(layer "B.Fab")
		)
		(fp_line
			(start 0.12065 -0.2794)
			(end -0.12065 -0.2794)
			(stroke
				(width 0.1)
				(type default)
			)
			(layer "B.Fab")
		)
		(fp_line
			(start 0.12065 -0.305054)
			(end 0.12065 -0.2794)
			(stroke
				(width 0.1)
				(type default)
			)
			(layer "B.Fab")
		)
		(fp_line
			(start -0.120396 0.3048)
			(end -0.120396 0.2794)
			(stroke
				(width 0.1)
				(type default)
			)
			(layer "B.Fab")
		)
		(fp_line
			(start -0.120396 0.2794)
			(end 0.12065 0.2794)
			(stroke
				(width 0.1)
				(type default)
			)
			(layer "B.Fab")
		)
		(fp_line
			(start -0.12065 -0.2794)
			(end -0.12065 -0.3048)
			(stroke
				(width 0.1)
				(type default)
			)
			(layer "B.Fab")
		)
		(fp_line
			(start -0.12065 -0.3048)
			(end -0.67945 -0.3048)
			(stroke
				(width 0.1)
				(type default)
			)
			(layer "B.Fab")
		)
		(fp_line
			(start -0.67945 0.3048)
			(end -0.120396 0.3048)
			(stroke
				(width 0.1)
				(type default)
			)
			(layer "B.Fab")
		)
		(fp_line
			(start -0.67945 -0.3048)
			(end -0.67945 0.3048)
			(stroke
				(width 0.1)
				(type default)
			)
			(layer "B.Fab")
		)
		(pad "1" smd circle
			(at 0.40005 0)
			(size 0 0)
			(layers "B.Cu" "B.Mask" "B.Paste")
			(net "PWRGD_PVDDIO_P1")
		)
		(pad "2" smd circle
			(at -0.40005 0)
			(size 0 0)
			(layers "B.Cu" "B.Mask" "B.Paste")
			(net "PWRGD_PVDDIO_P1_R")
		)
	)
	(footprint ""
		(layer "B.Cu")
		(at 428.98695 -38.039548 180)
		(property "Reference" "R6043"
			(at 0 0 0)
			(layer "B.SilkS")
			(hide yes)
			(effects
				(font
					(size 1.27 1.27)
				)
				(justify mirror)
			)
		)
		(property "Value" ""
			(at 0 0 0)
			(layer "B.Fab")
			(effects
				(font
					(size 1.27 1.27)
				)
				(justify mirror)
			)
		)
		(duplicate_pad_numbers_are_jumpers no)
		(fp_line
			(start 0.7874 0.4064)
			(end 0.7874 -0.4064)
			(stroke
				(width 0.1524)
				(type default)
			)
			(layer "B.SilkS")
		)
		(fp_line
			(start 0.7874 -0.4064)
			(end -0.7874 -0.4064)
			(stroke
				(width 0.1524)
				(type default)
			)
			(layer "B.SilkS")
		)
		(fp_line
			(start -0.7874 0.4064)
			(end 0.7874 0.4064)
			(stroke
				(width 0.1524)
				(type default)
			)
			(layer "B.SilkS")
		)
		(fp_line
			(start -0.7874 -0.4064)
			(end -0.7874 0.4064)
			(stroke
				(width 0.1524)
				(type default)
			)
			(layer "B.SilkS")
		)
		(fp_line
			(start 0.67945 0.3048)
			(end 0.67945 -0.305054)
			(stroke
				(width 0.1)
				(type default)
			)
			(layer "B.Fab")
		)
		(fp_line
			(start 0.67945 -0.305054)
			(end 0.12065 -0.305054)
			(stroke
				(width 0.1)
				(type default)
			)
			(layer "B.Fab")
		)
		(fp_line
			(start 0.12065 0.3048)
			(end 0.67945 0.3048)
			(stroke
				(width 0.1)
				(type default)
			)
			(layer "B.Fab")
		)
		(fp_line
			(start 0.12065 0.2794)
			(end 0.12065 0.3048)
			(stroke
				(width 0.1)
				(type default)
			)
			(layer "B.Fab")
		)
		(fp_line
			(start 0.12065 -0.2794)
			(end -0.12065 -0.2794)
			(stroke
				(width 0.1)
				(type default)
			)
			(layer "B.Fab")
		)
		(fp_line
			(start 0.12065 -0.305054)
			(end 0.12065 -0.2794)
			(stroke
				(width 0.1)
				(type default)
			)
			(layer "B.Fab")
		)
		(fp_line
			(start -0.120396 0.3048)
			(end -0.120396 0.2794)
			(stroke
				(width 0.1)
				(type default)
			)
			(layer "B.Fab")
		)
		(fp_line
			(start -0.120396 0.2794)
			(end 0.12065 0.2794)
			(stroke
				(width 0.1)
				(type default)
			)
			(layer "B.Fab")
		)
		(fp_line
			(start -0.12065 -0.2794)
			(end -0.12065 -0.3048)
			(stroke
				(width 0.1)
				(type default)
			)
			(layer "B.Fab")
		)
		(fp_line
			(start -0.12065 -0.3048)
			(end -0.67945 -0.3048)
			(stroke
				(width 0.1)
				(type default)
			)
			(layer "B.Fab")
		)
		(fp_line
			(start -0.67945 0.3048)
			(end -0.120396 0.3048)
			(stroke
				(width 0.1)
				(type default)
			)
			(layer "B.Fab")
		)
		(fp_line
			(start -0.67945 -0.3048)
			(end -0.67945 0.3048)
			(stroke
				(width 0.1)
				(type default)
			)
			(layer "B.Fab")
		)
		(pad "1" smd circle
			(at 0.40005 0)
			(size 0 0)
			(layers "B.Cu" "B.Mask" "B.Paste")
			(net "GND")
		)
		(pad "2" smd circle
			(at -0.40005 0)
			(size 0 0)
			(layers "B.Cu" "B.Mask" "B.Paste")
			(net "FPGA_DEBUG_SW_SPARE")
		)
	)
	(footprint ""
		(layer "B.Cu")
		(at 232.537 -338.455 -90)
		(property "Reference" "R6765"
			(at 0 0 90)
			(layer "B.SilkS")
			(hide yes)
			(effects
				(font
					(size 1.27 1.27)
				)
				(justify mirror)
			)
		)
		(property "Value" ""
			(at 0 0 90)
			(layer "B.Fab")
			(effects
				(font
					(size 1.27 1.27)
				)
				(justify mirror)
			)
		)
		(duplicate_pad_numbers_are_jumpers no)
		(fp_line
			(start -0.32512 0.175006)
			(end 0.32512 0.175006)
			(stroke
				(width 0.1)
				(type default)
			)
			(layer "B.Fab")
		)
		(fp_line
			(start 0.32512 0.175006)
			(end 0.32512 -0.175006)
			(stroke
				(width 0.1)
				(type default)
			)
			(layer "B.Fab")
		)
		(fp_line
			(start -0.32512 -0.175006)
			(end -0.32512 0.175006)
			(stroke
				(width 0.1)
				(type default)
			)
			(layer "B.Fab")
		)
		(fp_line
			(start 0.32512 -0.175006)
			(end -0.32512 -0.175006)
			(stroke
				(width 0.1)
				(type default)
			)
			(layer "B.Fab")
		)
		(pad "1" smd rect
			(at 0.2667 0 90)
			(size 0.3048 0.381)
			(layers "B.Cu" "B.Mask" "B.Paste")
			(net "P1V8_CPU0_RT_1D")
		)
		(pad "2" smd rect
			(at -0.2667 0 270)
			(size 0.3048 0.381)
			(layers "B.Cu" "B.Mask" "B.Paste")
			(net "SMB_RT_CPU0_P1_R_SCL")
		)
	)
)
